# T6G (Grand Teton) — schematic netlist excerpt (pin names and nets, part order shuffled) for the footprints in the layout excerpt that follows; sources: Cadence DE-HDL packaged netlist, KiCad conversion of 04192023_DAF0TMB3IC0_F0TG_MB_C_brd_V02_OCP.brd

C2119  Q_CAP  22UF 4V 20% X6S  pkg C0402  page 74 : A = PVDD11_S3_P1 ; B = GND
C1052  Q_CAP  0.1UF 10V 10% X7S  pkg C0201  page 312 : A = P0V9_CPU0_RT3_2A ; B = GND
C404  Q_CAP  100UF 4V 20% X6S  pkg C0805  page 345 : A = P0V9_CPU1_RT_2D ; B = GND
C1029  Q_CAP  100UF 4V 20% X6S  pkg C0805  page 312 : A = P0V9_CPU0_RT3_2A ; B = GND

(kicad_pcb
	(version 20260206)
	(generator "pcbnew")
	(generator_version "10.0")
	(general
		(thickness 1.6)
		(legacy_teardrops no)
	)
	(paper "A4")
	(title_block
		(title "04192023_DAF0TMB3IC0_F0TG_MB_C_brd_V02_OCP.brd")
		(comment 1 "Grand Teton / footprints 5286-5289 of 8354")
	)
	(layers
		(0 "F.Cu" signal "TOP")
		(4 "In1.Cu" signal "GND")
		(6 "In2.Cu" signal "IN1")
		(8 "In3.Cu" signal "GND1")
		(10 "In4.Cu" signal "IN2")
		(12 "In5.Cu" signal "GND2")
		(14 "In6.Cu" signal "IN3")
		(16 "In7.Cu" signal "GND3")
		(18 "In8.Cu" signal "VCC")
		(20 "In9.Cu" signal "VCC1")
		(22 "In10.Cu" signal "GND4")
		(24 "In11.Cu" signal "IN4")
		(26 "In12.Cu" signal "GND5")
		(28 "In13.Cu" signal "IN5")
		(30 "In14.Cu" signal "GND6")
		(32 "In15.Cu" signal "IN6")
		(34 "In16.Cu" signal "GND7")
		(2 "B.Cu" signal "BOTTOM")
		(9 "F.Adhes" user "F.Adhesive")
		(11 "B.Adhes" user "B.Adhesive")
		(13 "F.Paste" user "Package Geometry/Pastemask Top")
		(15 "B.Paste" user "Package Geometry/Pastemask Bottom")
		(5 "F.SilkS" user "Ref Des/Silkscreen Top")
		(7 "B.SilkS" user "Ref Des/Silkscreen Bottom")
		(1 "F.Mask" user "Board Geometry/Soldermask Top")
		(3 "B.Mask" user "Board Geometry/Soldermask Bottom")
		(17 "Dwgs.User" user "User.Drawings")
		(19 "Cmts.User" user "User.Comments")
		(21 "Eco1.User" user "User.Eco1")
		(23 "Eco2.User" user "User.Eco2")
		(25 "Edge.Cuts" user "Board Geometry/Outline")
		(27 "Margin" user)
		(31 "F.CrtYd" user "Package Geometry/Place Bound Top")
		(29 "B.CrtYd" user "Package Geometry/Place Bound Bottom")
		(35 "F.Fab" user "Ref Des/Assembly Top")
		(33 "B.Fab" user "Ref Des/Assembly Bottom")
	)
	(footprint ""
		(layer "B.Cu")
		(at 119.674386 -264.354564)
		(property "Reference" "C2119"
			(at 0 0 0)
			(layer "B.SilkS")
			(hide yes)
			(effects
				(font
					(size 1.27 1.27)
				)
				(justify mirror)
			)
		)
		(property "Value" ""
			(at 0 0 0)
			(layer "B.Fab")
			(effects
				(font
					(size 1.27 1.27)
				)
				(justify mirror)
			)
		)
		(duplicate_pad_numbers_are_jumpers no)
		(fp_line
			(start -0.7874 -0.4064)
			(end -0.7874 0.4064)
			(stroke
				(width 0.1524)
				(type default)
			)
			(layer "B.SilkS")
		)
		(fp_line
			(start -0.7874 0.4064)
			(end 0.7874 0.4064)
			(stroke
				(width 0.1524)
				(type default)
			)
			(layer "B.SilkS")
		)
		(fp_line
			(start 0.7874 -0.4064)
			(end -0.7874 -0.4064)
			(stroke
				(width 0.1524)
				(type default)
			)
			(layer "B.SilkS")
		)
		(fp_line
			(start 0.7874 0.4064)
			(end 0.7874 -0.4064)
			(stroke
				(width 0.1524)
				(type default)
			)
			(layer "B.SilkS")
		)
		(fp_line
			(start -0.67945 -0.3048)
			(end -0.67945 0.3048)
			(stroke
				(width 0.1)
				(type default)
			)
			(layer "B.Fab")
		)
		(fp_line
			(start -0.67945 0.3048)
			(end -0.120396 0.3048)
			(stroke
				(width 0.1)
				(type default)
			)
			(layer "B.Fab")
		)
		(fp_line
			(start -0.12065 -0.3048)
			(end -0.67945 -0.3048)
			(stroke
				(width 0.1)
				(type default)
			)
			(layer "B.Fab")
		)
		(fp_line
			(start -0.12065 -0.2794)
			(end -0.12065 -0.3048)
			(stroke
				(width 0.1)
				(type default)
			)
			(layer "B.Fab")
		)
		(fp_line
			(start -0.120396 0.2794)
			(end 0.12065 0.2794)
			(stroke
				(width 0.1)
				(type default)
			)
			(layer "B.Fab")
		)
		(fp_line
			(start -0.120396 0.3048)
			(end -0.120396 0.2794)
			(stroke
				(width 0.1)
				(type default)
			)
			(layer "B.Fab")
		)
		(fp_line
			(start 0.12065 -0.305054)
			(end 0.12065 -0.2794)
			(stroke
				(width 0.1)
				(type default)
			)
			(layer "B.Fab")
		)
		(fp_line
			(start 0.12065 -0.2794)
			(end -0.12065 -0.2794)
			(stroke
				(width 0.1)
				(type default)
			)
			(layer "B.Fab")
		)
		(fp_line
			(start 0.12065 0.2794)
			(end 0.12065 0.3048)
			(stroke
				(width 0.1)
				(type default)
			)
			(layer "B.Fab")
		)
		(fp_line
			(start 0.12065 0.3048)
			(end 0.67945 0.3048)
			(stroke
				(width 0.1)
				(type default)
			)
			(layer "B.Fab")
		)
		(fp_line
			(start 0.67945 -0.305054)
			(end 0.12065 -0.305054)
			(stroke
				(width 0.1)
				(type default)
			)
			(layer "B.Fab")
		)
		(fp_line
			(start 0.67945 0.3048)
			(end 0.67945 -0.305054)
			(stroke
				(width 0.1)
				(type default)
			)
			(layer "B.Fab")
		)
		(pad "1" smd circle
			(at 0.40005 0 180)
			(size 0 0)
			(layers "B.Cu" "B.Mask" "B.Paste")
			(net "PVDD11_S3_P1")
		)
		(pad "2" smd circle
			(at -0.40005 0 180)
			(size 0 0)
			(layers "B.Cu" "B.Mask" "B.Paste")
			(net "GND")
		)
	)
	(footprint ""
		(layer "B.Cu")
		(at 139.562586 -389.673084 90)
		(property "Reference" "C404"
			(at 0 0 90)
			(layer "B.SilkS")
			(hide yes)
			(effects
				(font
					(size 1.27 1.27)
				)
				(justify mirror)
			)
		)
		(property "Value" ""
			(at 0 0 90)
			(layer "B.Fab")
			(effects
				(font
					(size 1.27 1.27)
				)
				(justify mirror)
			)
		)
		(duplicate_pad_numbers_are_jumpers no)
		(fp_line
			(start 1.524 -0.762)
			(end -1.524 -0.762)
			(stroke
				(width 0.1524)
				(type default)
			)
			(layer "B.SilkS")
		)
		(fp_line
			(start -1.524 -0.762)
			(end -1.524 0.762)
			(stroke
				(width 0.1524)
				(type default)
			)
			(layer "B.SilkS")
		)
		(fp_line
			(start 1.524 0.762)
			(end 1.524 -0.762)
			(stroke
				(width 0.1524)
				(type default)
			)
			(layer "B.SilkS")
		)
		(fp_line
			(start -1.524 0.762)
			(end 1.524 0.762)
			(stroke
				(width 0.1524)
				(type default)
			)
			(layer "B.SilkS")
		)
		(fp_line
			(start 1.1049 -0.724916)
			(end 1.1049 0.724916)
			(stroke
				(width 0.1)
				(type default)
			)
			(layer "B.Fab")
		)
		(fp_line
			(start -1.1049 -0.724916)
			(end 1.1049 -0.724916)
			(stroke
				(width 0.1)
				(type default)
			)
			(layer "B.Fab")
		)
		(fp_line
			(start 1.1049 0.724916)
			(end -1.1049 0.724916)
			(stroke
				(width 0.1)
				(type default)
			)
			(layer "B.Fab")
		)
		(fp_line
			(start -1.1049 0.724916)
			(end -1.1049 -0.724916)
			(stroke
				(width 0.1)
				(type default)
			)
			(layer "B.Fab")
		)
		(pad "1" smd rect
			(at 0.889 0 90)
			(size 1.016 1.27)
			(layers "B.Cu" "B.Mask" "B.Paste")
			(net "P0V9_CPU1_RT_2D")
		)
		(pad "2" smd rect
			(at -0.889 0 90)
			(size 1.016 1.27)
			(layers "B.Cu" "B.Mask" "B.Paste")
			(net "GND")
		)
	)
	(footprint ""
		(layer "B.Cu")
		(at 370.618512 -396.393162 -90)
		(property "Reference" "C1052"
			(at 0 0 90)
			(layer "B.SilkS")
			(hide yes)
			(effects
				(font
					(size 1.27 1.27)
				)
				(justify mirror)
			)
		)
		(property "Value" ""
			(at 0 0 90)
			(layer "B.Fab")
			(effects
				(font
					(size 1.27 1.27)
				)
				(justify mirror)
			)
		)
		(duplicate_pad_numbers_are_jumpers no)
		(fp_line
			(start -0.299974 0.150114)
			(end 0.299974 0.150114)
			(stroke
				(width 0.1)
				(type default)
			)
			(layer "B.Fab")
		)
		(fp_line
			(start 0.299974 0.150114)
			(end 0.299974 -0.150114)
			(stroke
				(width 0.1)
				(type default)
			)
			(layer "B.Fab")
		)
		(fp_line
			(start -0.299974 -0.150114)
			(end -0.299974 0.150114)
			(stroke
				(width 0.1)
				(type default)
			)
			(layer "B.Fab")
		)
		(fp_line
			(start 0.299974 -0.150114)
			(end -0.299974 -0.150114)
			(stroke
				(width 0.1)
				(type default)
			)
			(layer "B.Fab")
		)
		(pad "1" smd rect
			(at 0.2667 0 90)
			(size 0.3048 0.381)
			(layers "B.Cu" "B.Mask" "B.Paste")
			(net "P0V9_CPU0_RT3_2A")
		)
		(pad "2" smd rect
			(at -0.2667 0 90)
			(size 0.3048 0.381)
			(layers "B.Cu" "B.Mask" "B.Paste")
			(net "GND")
		)
	)
	(footprint ""
		(layer "B.Cu")
		(at 365.519462 -398.969484)
		(property "Reference" "C1029"
			(at 0 0 0)
			(layer "B.SilkS")
			(hide yes)
			(effects
				(font
					(size 1.27 1.27)
				)
				(justify mirror)
			)
		)
		(property "Value" ""
			(at 0 0 0)
			(layer "B.Fab")
			(effects
				(font
					(size 1.27 1.27)
				)
				(justify mirror)
			)
		)
		(duplicate_pad_numbers_are_jumpers no)
		(fp_line
			(start -1.524 -0.762)
			(end -1.524 0.762)
			(stroke
				(width 0.1524)
				(type default)
			)
			(layer "B.SilkS")
		)
		(fp_line
			(start -1.524 0.762)
			(end 1.524 0.762)
			(stroke
				(width 0.1524)
				(type default)
			)
			(layer "B.SilkS")
		)
		(fp_line
			(start 1.524 -0.762)
			(end -1.524 -0.762)
			(stroke
				(width 0.1524)
				(type default)
			)
			(layer "B.SilkS")
		)
		(fp_line
			(start 1.524 0.762)
			(end 1.524 -0.762)
			(stroke
				(width 0.1524)
				(type default)
			)
			(layer "B.SilkS")
		)
		(fp_line
			(start -1.1049 -0.724916)
			(end 1.1049 -0.724916)
			(stroke
				(width 0.1)
				(type default)
			)
			(layer "B.Fab")
		)
		(fp_line
			(start -1.1049 0.724916)
			(end -1.1049 -0.724916)
			(stroke
				(width 0.1)
				(type default)
			)
			(layer "B.Fab")
		)
		(fp_line
			(start 1.1049 -0.724916)
			(end 1.1049 0.724916)
			(stroke
				(width 0.1)
				(type default)
			)
			(layer "B.Fab")
		)
		(fp_line
			(start 1.1049 0.724916)
			(end -1.1049 0.724916)
			(stroke
				(width 0.1)
				(type default)
			)
			(layer "B.Fab")
		)
		(pad "1" smd rect
			(at 0.889 0)
			(size 1.016 1.27)
			(layers "B.Cu" "B.Mask" "B.Paste")
			(net "P0V9_CPU0_RT3_2A")
		)
		(pad "2" smd rect
			(at -0.889 0)
			(size 1.016 1.27)
			(layers "B.Cu" "B.Mask" "B.Paste")
			(net "GND")
		)
	)
)
